(kicad_pcb
	(version 20260206)
	(generator "pcbnew")
	(generator_version "10.0")
	(general
		(thickness 1.6)
		(legacy_teardrops no)
	)
	(paper "A4")
	(title_block
		(title "01162023_DA0F0TEBIF0_F0T_Expander_BD_F_brd_V02_OCP.brd")
		(comment 1 "Grand Teton / footprints 2554-2559 of 9728")
	)
	(layers
		(0 "F.Cu" signal "TOP")
		(4 "In1.Cu" signal "GND")
		(6 "In2.Cu" signal "VCC")
		(8 "In3.Cu" signal "VCC1")
		(10 "In4.Cu" signal "GND1")
		(12 "In5.Cu" signal "IN1")
		(14 "In6.Cu" signal "GND2")
		(16 "In7.Cu" signal "IN2")
		(18 "In8.Cu" signal "GND3")
		(20 "In9.Cu" signal "IN3")
		(22 "In10.Cu" signal "GND4")
		(24 "In11.Cu" signal "IN4")
		(26 "In12.Cu" signal "GND5")
		(28 "In13.Cu" signal "IN5")
		(30 "In14.Cu" signal "GND6")
		(32 "In15.Cu" signal "IN6")
		(34 "In16.Cu" signal "GND7")
		(2 "B.Cu" signal "BOTTOM")
		(9 "F.Adhes" user "F.Adhesive")
		(11 "B.Adhes" user "B.Adhesive")
		(13 "F.Paste" user "Package Geometry/Pastemask Top")
		(15 "B.Paste" user "Package Geometry/Pastemask Bottom")
		(5 "F.SilkS" user "Ref Des/Silkscreen Top")
		(7 "B.SilkS" user "Ref Des/Silkscreen Bottom")
		(1 "F.Mask" user "Board Geometry/Soldermask Top")
		(3 "B.Mask" user "Board Geometry/Soldermask Bottom")
		(17 "Dwgs.User" user "User.Drawings")
		(19 "Cmts.User" user "User.Comments")
		(21 "Eco1.User" user "User.Eco1")
		(23 "Eco2.User" user "User.Eco2")
		(25 "Edge.Cuts" user "Board Geometry/Outline")
		(27 "Margin" user)
		(31 "F.CrtYd" user "Package Geometry/Place Bound Top")
		(29 "B.CrtYd" user "Package Geometry/Place Bound Bottom")
		(35 "F.Fab" user "Ref Des/Assembly Top")
		(33 "B.Fab" user "Ref Des/Assembly Bottom")
	)
	(footprint ""
		(layer "F.Cu")
		(at 270.982694 -141.87297)
		(property "Reference" "R236"
			(at 0 0 0)
			(layer "F.SilkS")
			(hide yes)
			(effects
				(font
					(size 1.27 1.27)
				)
			)
		)
		(property "Value" ""
			(at 0 0 0)
			(layer "F.Fab")
			(effects
				(font
					(size 1.27 1.27)
				)
			)
		)
		(duplicate_pad_numbers_are_jumpers no)
		(fp_line
			(start -0.7874 -0.4064)
			(end 0.7874 -0.4064)
			(stroke
				(width 0.1524)
				(type default)
			)
			(layer "F.SilkS")
		)
		(fp_line
			(start -0.7874 0.4064)
			(end -0.7874 -0.4064)
			(stroke
				(width 0.1524)
				(type default)
			)
			(layer "F.SilkS")
		)
		(fp_line
			(start 0.7874 -0.4064)
			(end 0.7874 0.4064)
			(stroke
				(width 0.1524)
				(type default)
			)
			(layer "F.SilkS")
		)
		(fp_line
			(start 0.7874 0.4064)
			(end -0.7874 0.4064)
			(stroke
				(width 0.1524)
				(type default)
			)
			(layer "F.SilkS")
		)
		(fp_line
			(start -0.67945 -0.305054)
			(end -0.12065 -0.305054)
			(stroke
				(width 0.1)
				(type default)
			)
			(layer "F.Fab")
		)
		(fp_line
			(start -0.67945 0.3048)
			(end -0.67945 -0.305054)
			(stroke
				(width 0.1)
				(type default)
			)
			(layer "F.Fab")
		)
		(fp_line
			(start -0.12065 -0.305054)
			(end -0.12065 -0.2794)
			(stroke
				(width 0.1)
				(type default)
			)
			(layer "F.Fab")
		)
		(fp_line
			(start -0.12065 -0.2794)
			(end 0.12065 -0.2794)
			(stroke
				(width 0.1)
				(type default)
			)
			(layer "F.Fab")
		)
		(fp_line
			(start -0.12065 0.2794)
			(end -0.12065 0.3048)
			(stroke
				(width 0.1)
				(type default)
			)
			(layer "F.Fab")
		)
		(fp_line
			(start -0.12065 0.3048)
			(end -0.67945 0.3048)
			(stroke
				(width 0.1)
				(type default)
			)
			(layer "F.Fab")
		)
		(fp_line
			(start 0.120396 0.2794)
			(end -0.12065 0.2794)
			(stroke
				(width 0.1)
				(type default)
			)
			(layer "F.Fab")
		)
		(fp_line
			(start 0.120396 0.3048)
			(end 0.120396 0.2794)
			(stroke
				(width 0.1)
				(type default)
			)
			(layer "F.Fab")
		)
		(fp_line
			(start 0.12065 -0.3048)
			(end 0.67945 -0.3048)
			(stroke
				(width 0.1)
				(type default)
			)
			(layer "F.Fab")
		)
		(fp_line
			(start 0.12065 -0.2794)
			(end 0.12065 -0.3048)
			(stroke
				(width 0.1)
				(type default)
			)
			(layer "F.Fab")
		)
		(fp_line
			(start 0.67945 -0.3048)
			(end 0.67945 0.3048)
			(stroke
				(width 0.1)
				(type default)
			)
			(layer "F.Fab")
		)
		(fp_line
			(start 0.67945 0.3048)
			(end 0.120396 0.3048)
			(stroke
				(width 0.1)
				(type default)
			)
			(layer "F.Fab")
		)
		(pad "1" smd circle
			(at -0.40005 0)
			(size 0 0)
			(layers "F.Cu" "F.Mask" "F.Paste")
			(net "NIC4_BIF1_N")
		)
		(pad "2" smd circle
			(at 0.40005 0)
			(size 0 0)
			(layers "F.Cu" "F.Mask" "F.Paste")
			(net "GND")
		)
	)
	(footprint ""
		(layer "F.Cu")
		(at 369.477036 -124.008134 90)
		(property "Reference" "PD57"
			(at -3.459734 2.278634 90)
			(unlocked yes)
			(layer "F.SilkS")
			(effects
				(font
					(size 0.7874 0.5842)
					(thickness 0.1524)
				)
				(justify left)
			)
		)
		(property "Value" ""
			(at 0 0 90)
			(layer "F.Fab")
			(effects
				(font
					(size 1.27 1.27)
				)
			)
		)
		(duplicate_pad_numbers_are_jumpers no)
		(fp_line
			(start 4.107942 -1.459992)
			(end 4.107942 1.459992)
			(stroke
				(width 0.1524)
				(type default)
			)
			(layer "F.SilkS")
		)
		(fp_line
			(start -3.400044 -1.459992)
			(end 4.107942 -1.459992)
			(stroke
				(width 0.1524)
				(type default)
			)
			(layer "F.SilkS")
		)
		(fp_line
			(start 4.107942 1.459992)
			(end -3.400044 1.459992)
			(stroke
				(width 0.1524)
				(type default)
			)
			(layer "F.SilkS")
		)
		(fp_line
			(start -3.400044 1.459992)
			(end -3.400044 -1.459992)
			(stroke
				(width 0.1524)
				(type default)
			)
			(layer "F.SilkS")
		)
		(fp_poly
			(pts
				(xy 4.107942 -1.459992) (xy 4.107942 1.459992) (xy 3.308096 1.459992) (xy 3.308096 -1.459992)
			)
			(stroke
				(width 0)
				(type default)
			)
			(fill yes)
			(layer "F.SilkS")
		)
		(fp_line
			(start 2.29997 -1.459992)
			(end 2.29997 1.459992)
			(stroke
				(width 0.1)
				(type default)
			)
			(layer "F.Fab")
		)
		(fp_line
			(start -2.29997 -1.459992)
			(end 2.29997 -1.459992)
			(stroke
				(width 0.1)
				(type default)
			)
			(layer "F.Fab")
		)
		(fp_line
			(start 2.29997 1.459992)
			(end -2.29997 1.459992)
			(stroke
				(width 0.1)
				(type default)
			)
			(layer "F.Fab")
		)
		(fp_line
			(start -2.29997 1.459992)
			(end -2.29997 -1.459992)
			(stroke
				(width 0.1)
				(type default)
			)
			(layer "F.Fab")
		)
		(fp_text user "+"
			(at -4.7752 -0.12065 90)
			(unlocked yes)
			(layer "F.SilkS")
			(effects
				(font
					(size 1.905 1.4224)
					(thickness 0.1524)
				)
				(justify left)
			)
		)
		(fp_text user "-"
			(at 5.4102 0.29845 270)
			(unlocked yes)
			(layer "F.SilkS")
			(effects
				(font
					(size 1.905 1.4224)
					(thickness 0.1524)
				)
				(justify left)
			)
		)
		(fp_text user "+"
			(at -4.7752 -0.12065 90)
			(unlocked yes)
			(layer "F.Fab")
			(effects
				(font
					(size 1.905 1.4224)
					(thickness 0.1524)
				)
				(justify left)
			)
		)
		(fp_text user "-"
			(at 5.4102 0.29845 270)
			(unlocked yes)
			(layer "F.Fab")
			(effects
				(font
					(size 1.905 1.4224)
					(thickness 0.1524)
				)
				(justify left)
			)
		)
		(pad "A" smd rect
			(at -1.999996 0 180)
			(size 1.7018 2.5146)
			(layers "F.Cu" "F.Mask" "F.Paste")
			(net "GND")
		)
		(pad "C" smd rect
			(at 1.999996 0 180)
			(size 1.7018 2.5146)
			(layers "F.Cu" "F.Mask" "F.Paste")
			(net "P3V3_NIC6")
		)
	)
	(footprint ""
		(layer "F.Cu")
		(at 34.120582 -26.666444 -90)
		(property "Reference" "R4052"
			(at 0 0 270)
			(layer "F.SilkS")
			(hide yes)
			(effects
				(font
					(size 1.27 1.27)
				)
			)
		)
		(property "Value" ""
			(at 0 0 270)
			(layer "F.Fab")
			(effects
				(font
					(size 1.27 1.27)
				)
			)
		)
		(duplicate_pad_numbers_are_jumpers no)
		(fp_line
			(start -0.7874 0.4064)
			(end -0.7874 -0.4064)
			(stroke
				(width 0.1524)
				(type default)
			)
			(layer "F.SilkS")
		)
		(fp_line
			(start 0.7874 0.4064)
			(end -0.7874 0.4064)
			(stroke
				(width 0.1524)
				(type default)
			)
			(layer "F.SilkS")
		)
		(fp_line
			(start -0.7874 -0.4064)
			(end 0.7874 -0.4064)
			(stroke
				(width 0.1524)
				(type default)
			)
			(layer "F.SilkS")
		)
		(fp_line
			(start 0.7874 -0.4064)
			(end 0.7874 0.4064)
			(stroke
				(width 0.1524)
				(type default)
			)
			(layer "F.SilkS")
		)
		(fp_line
			(start -0.67945 0.3048)
			(end -0.67945 -0.305054)
			(stroke
				(width 0.1)
				(type default)
			)
			(layer "F.Fab")
		)
		(fp_line
			(start -0.12065 0.3048)
			(end -0.67945 0.3048)
			(stroke
				(width 0.1)
				(type default)
			)
			(layer "F.Fab")
		)
		(fp_line
			(start 0.120396 0.3048)
			(end 0.120396 0.2794)
			(stroke
				(width 0.1)
				(type default)
			)
			(layer "F.Fab")
		)
		(fp_line
			(start 0.67945 0.3048)
			(end 0.120396 0.3048)
			(stroke
				(width 0.1)
				(type default)
			)
			(layer "F.Fab")
		)
		(fp_line
			(start -0.12065 0.2794)
			(end -0.12065 0.3048)
			(stroke
				(width 0.1)
				(type default)
			)
			(layer "F.Fab")
		)
		(fp_line
			(start 0.120396 0.2794)
			(end -0.12065 0.2794)
			(stroke
				(width 0.1)
				(type default)
			)
			(layer "F.Fab")
		)
		(fp_line
			(start -0.12065 -0.2794)
			(end 0.12065 -0.2794)
			(stroke
				(width 0.1)
				(type default)
			)
			(layer "F.Fab")
		)
		(fp_line
			(start 0.12065 -0.2794)
			(end 0.12065 -0.3048)
			(stroke
				(width 0.1)
				(type default)
			)
			(layer "F.Fab")
		)
		(fp_line
			(start 0.12065 -0.3048)
			(end 0.67945 -0.3048)
			(stroke
				(width 0.1)
				(type default)
			)
			(layer "F.Fab")
		)
		(fp_line
			(start 0.67945 -0.3048)
			(end 0.67945 0.3048)
			(stroke
				(width 0.1)
				(type default)
			)
			(layer "F.Fab")
		)
		(fp_line
			(start -0.67945 -0.305054)
			(end -0.12065 -0.305054)
			(stroke
				(width 0.1)
				(type default)
			)
			(layer "F.Fab")
		)
		(fp_line
			(start -0.12065 -0.305054)
			(end -0.12065 -0.2794)
			(stroke
				(width 0.1)
				(type default)
			)
			(layer "F.Fab")
		)
		(pad "1" smd circle
			(at -0.40005 0 270)
			(size 0 0)
			(layers "F.Cu" "F.Mask" "F.Paste")
			(net "PRSNT_SSD1_R_N")
		)
		(pad "2" smd circle
			(at 0.40005 0 270)
			(size 0 0)
			(layers "F.Cu" "F.Mask" "F.Paste")
			(net "PRSNT_SSD1_N")
		)
	)
	(footprint ""
		(layer "F.Cu")
		(at 140.892784 -257.148838 -90)
		(property "Reference" "R1327"
			(at 0 0 270)
			(layer "F.SilkS")
			(hide yes)
			(effects
				(font
					(size 1.27 1.27)
				)
			)
		)
		(property "Value" ""
			(at 0 0 270)
			(layer "F.Fab")
			(effects
				(font
					(size 1.27 1.27)
				)
			)
		)
		(duplicate_pad_numbers_are_jumpers no)
		(fp_line
			(start -0.7874 0.4064)
			(end -0.7874 -0.4064)
			(stroke
				(width 0.1524)
				(type default)
			)
			(layer "F.SilkS")
		)
		(fp_line
			(start 0.7874 0.4064)
			(end -0.7874 0.4064)
			(stroke
				(width 0.1524)
				(type default)
			)
			(layer "F.SilkS")
		)
		(fp_line
			(start -0.7874 -0.4064)
			(end 0.7874 -0.4064)
			(stroke
				(width 0.1524)
				(type default)
			)
			(layer "F.SilkS")
		)
		(fp_line
			(start 0.7874 -0.4064)
			(end 0.7874 0.4064)
			(stroke
				(width 0.1524)
				(type default)
			)
			(layer "F.SilkS")
		)
		(fp_line
			(start -0.67945 0.3048)
			(end -0.67945 -0.305054)
			(stroke
				(width 0.1)
				(type default)
			)
			(layer "F.Fab")
		)
		(fp_line
			(start -0.12065 0.3048)
			(end -0.67945 0.3048)
			(stroke
				(width 0.1)
				(type default)
			)
			(layer "F.Fab")
		)
		(fp_line
			(start 0.120396 0.3048)
			(end 0.120396 0.2794)
			(stroke
				(width 0.1)
				(type default)
			)
			(layer "F.Fab")
		)
		(fp_line
			(start 0.67945 0.3048)
			(end 0.120396 0.3048)
			(stroke
				(width 0.1)
				(type default)
			)
			(layer "F.Fab")
		)
		(fp_line
			(start -0.12065 0.2794)
			(end -0.12065 0.3048)
			(stroke
				(width 0.1)
				(type default)
			)
			(layer "F.Fab")
		)
		(fp_line
			(start 0.120396 0.2794)
			(end -0.12065 0.2794)
			(stroke
				(width 0.1)
				(type default)
			)
			(layer "F.Fab")
		)
		(fp_line
			(start -0.12065 -0.2794)
			(end 0.12065 -0.2794)
			(stroke
				(width 0.1)
				(type default)
			)
			(layer "F.Fab")
		)
		(fp_line
			(start 0.12065 -0.2794)
			(end 0.12065 -0.3048)
			(stroke
				(width 0.1)
				(type default)
			)
			(layer "F.Fab")
		)
		(fp_line
			(start 0.12065 -0.3048)
			(end 0.67945 -0.3048)
			(stroke
				(width 0.1)
				(type default)
			)
			(layer "F.Fab")
		)
		(fp_line
			(start 0.67945 -0.3048)
			(end 0.67945 0.3048)
			(stroke
				(width 0.1)
				(type default)
			)
			(layer "F.Fab")
		)
		(fp_line
			(start -0.67945 -0.305054)
			(end -0.12065 -0.305054)
			(stroke
				(width 0.1)
				(type default)
			)
			(layer "F.Fab")
		)
		(fp_line
			(start -0.12065 -0.305054)
			(end -0.12065 -0.2794)
			(stroke
				(width 0.1)
				(type default)
			)
			(layer "F.Fab")
		)
		(pad "1" smd circle
			(at -0.40005 0 270)
			(size 0 0)
			(layers "F.Cu" "F.Mask" "F.Paste")
			(net "P3V3_LED")
		)
		(pad "2" smd circle
			(at 0.40005 0 270)
			(size 0 0)
			(layers "F.Cu" "F.Mask" "F.Paste")
			(net "LED_PEX1_SYS_ERR_N")
		)
	)
	(footprint ""
		(layer "F.Cu")
		(at 175.0949 -101.782372 180)
		(property "Reference" "R174"
			(at 0 0 180)
			(layer "F.SilkS")
			(hide yes)
			(effects
				(font
					(size 1.27 1.27)
				)
			)
		)
		(property "Value" ""
			(at 0 0 180)
			(layer "F.Fab")
			(effects
				(font
					(size 1.27 1.27)
				)
			)
		)
		(duplicate_pad_numbers_are_jumpers no)
		(fp_line
			(start 0.7874 0.4064)
			(end -0.7874 0.4064)
			(stroke
				(width 0.1524)
				(type default)
			)
			(layer "F.SilkS")
		)
		(fp_line
			(start 0.7874 -0.4064)
			(end 0.7874 0.4064)
			(stroke
				(width 0.1524)
				(type default)
			)
			(layer "F.SilkS")
		)
		(fp_line
			(start -0.7874 0.4064)
			(end -0.7874 -0.4064)
			(stroke
				(width 0.1524)
				(type default)
			)
			(layer "F.SilkS")
		)
		(fp_line
			(start -0.7874 -0.4064)
			(end 0.7874 -0.4064)
			(stroke
				(width 0.1524)
				(type default)
			)
			(layer "F.SilkS")
		)
		(fp_line
			(start 0.67945 0.3048)
			(end 0.120396 0.3048)
			(stroke
				(width 0.1)
				(type default)
			)
			(layer "F.Fab")
		)
		(fp_line
			(start 0.67945 -0.3048)
			(end 0.67945 0.3048)
			(stroke
				(width 0.1)
				(type default)
			)
			(layer "F.Fab")
		)
		(fp_line
			(start 0.12065 -0.2794)
			(end 0.12065 -0.3048)
			(stroke
				(width 0.1)
				(type default)
			)
			(layer "F.Fab")
		)
		(fp_line
			(start 0.12065 -0.3048)
			(end 0.67945 -0.3048)
			(stroke
				(width 0.1)
				(type default)
			)
			(layer "F.Fab")
		)
		(fp_line
			(start 0.120396 0.3048)
			(end 0.120396 0.2794)
			(stroke
				(width 0.1)
				(type default)
			)
			(layer "F.Fab")
		)
		(fp_line
			(start 0.120396 0.2794)
			(end -0.12065 0.2794)
			(stroke
				(width 0.1)
				(type default)
			)
			(layer "F.Fab")
		)
		(fp_line
			(start -0.12065 0.3048)
			(end -0.67945 0.3048)
			(stroke
				(width 0.1)
				(type default)
			)
			(layer "F.Fab")
		)
		(fp_line
			(start -0.12065 0.2794)
			(end -0.12065 0.3048)
			(stroke
				(width 0.1)
				(type default)
			)
			(layer "F.Fab")
		)
		(fp_line
			(start -0.12065 -0.2794)
			(end 0.12065 -0.2794)
			(stroke
				(width 0.1)
				(type default)
			)
			(layer "F.Fab")
		)
		(fp_line
			(start -0.12065 -0.305054)
			(end -0.12065 -0.2794)
			(stroke
				(width 0.1)
				(type default)
			)
			(layer "F.Fab")
		)
		(fp_line
			(start -0.67945 0.3048)
			(end -0.67945 -0.305054)
			(stroke
				(width 0.1)
				(type default)
			)
			(layer "F.Fab")
		)
		(fp_line
			(start -0.67945 -0.305054)
			(end -0.12065 -0.305054)
			(stroke
				(width 0.1)
				(type default)
			)
			(layer "F.Fab")
		)
		(pad "1" smd circle
			(at -0.40005 0 180)
			(size 0 0)
			(layers "F.Cu" "F.Mask" "F.Paste")
			(net "NCSI_NIC3_TX_EN")
		)
		(pad "2" smd circle
			(at 0.40005 0 180)
			(size 0 0)
			(layers "F.Cu" "F.Mask" "F.Paste")
			(net "GND")
		)
	)
	(footprint ""
		(layer "F.Cu")
		(at 43.792394 -29.139642 180)
		(property "Reference" "C79"
			(at 0 0 180)
			(layer "F.SilkS")
			(hide yes)
			(effects
				(font
					(size 1.27 1.27)
				)
			)
		)
		(property "Value" ""
			(at 0 0 180)
			(layer "F.Fab")
			(effects
				(font
					(size 1.27 1.27)
				)
			)
		)
		(duplicate_pad_numbers_are_jumpers no)
		(fp_line
			(start 0.299974 0.150114)
			(end -0.299974 0.150114)
			(stroke
				(width 0.1)
				(type default)
			)
			(layer "F.Fab")
		)
		(fp_line
			(start 0.299974 -0.150114)
			(end 0.299974 0.150114)
			(stroke
				(width 0.1)
				(type default)
			)
			(layer "F.Fab")
		)
		(fp_line
			(start -0.299974 0.150114)
			(end -0.299974 -0.150114)
			(stroke
				(width 0.1)
				(type default)
			)
			(layer "F.Fab")
		)
		(fp_line
			(start -0.299974 -0.150114)
			(end 0.299974 -0.150114)
			(stroke
				(width 0.1)
				(type default)
			)
			(layer "F.Fab")
		)
		(pad "1" smd rect
			(at -0.2667 0 180)
			(size 0.3048 0.381)
			(layers "F.Cu" "F.Mask" "F.Paste")
			(net "P5E_PEX0_STN2_TX_DP<40>")
		)
		(pad "2" smd rect
			(at 0.2667 0 180)
			(size 0.3048 0.381)
			(layers "F.Cu" "F.Mask" "F.Paste")
			(net "P5E_PEX0_STN2_TX_C_DP<40>")
		)
	)
)
